(kicad_pcb
	(version 20260206)
	(generator "pcbnew")
	(generator_version "10.0")
	(general
		(thickness 1.6)
		(legacy_teardrops no)
	)
	(paper "A4")
	(title_block
		(title "01162023_DA0F0TEBIF0_F0T_Expander_BD_F_brd_V02_OCP.brd")
		(comment 1 "Grand Teton / footprints 1922-1928 of 9728")
	)
	(layers
		(0 "F.Cu" signal "TOP")
		(4 "In1.Cu" signal "GND")
		(6 "In2.Cu" signal "VCC")
		(8 "In3.Cu" signal "VCC1")
		(10 "In4.Cu" signal "GND1")
		(12 "In5.Cu" signal "IN1")
		(14 "In6.Cu" signal "GND2")
		(16 "In7.Cu" signal "IN2")
		(18 "In8.Cu" signal "GND3")
		(20 "In9.Cu" signal "IN3")
		(22 "In10.Cu" signal "GND4")
		(24 "In11.Cu" signal "IN4")
		(26 "In12.Cu" signal "GND5")
		(28 "In13.Cu" signal "IN5")
		(30 "In14.Cu" signal "GND6")
		(32 "In15.Cu" signal "IN6")
		(34 "In16.Cu" signal "GND7")
		(2 "B.Cu" signal "BOTTOM")
		(9 "F.Adhes" user "F.Adhesive")
		(11 "B.Adhes" user "B.Adhesive")
		(13 "F.Paste" user "Package Geometry/Pastemask Top")
		(15 "B.Paste" user "Package Geometry/Pastemask Bottom")
		(5 "F.SilkS" user "Ref Des/Silkscreen Top")
		(7 "B.SilkS" user "Ref Des/Silkscreen Bottom")
		(1 "F.Mask" user "Board Geometry/Soldermask Top")
		(3 "B.Mask" user "Board Geometry/Soldermask Bottom")
		(17 "Dwgs.User" user "User.Drawings")
		(19 "Cmts.User" user "User.Comments")
		(21 "Eco1.User" user "User.Eco1")
		(23 "Eco2.User" user "User.Eco2")
		(25 "Edge.Cuts" user "Board Geometry/Outline")
		(27 "Margin" user)
		(31 "F.CrtYd" user "Package Geometry/Place Bound Top")
		(29 "B.CrtYd" user "Package Geometry/Place Bound Bottom")
		(35 "F.Fab" user "Ref Des/Assembly Top")
		(33 "B.Fab" user "Ref Des/Assembly Bottom")
	)
	(footprint ""
		(layer "F.Cu")
		(at 136.445244 -92.385642 180)
		(property "Reference" "R1584"
			(at 0 0 180)
			(layer "F.SilkS")
			(hide yes)
			(effects
				(font
					(size 1.27 1.27)
				)
			)
		)
		(property "Value" ""
			(at 0 0 180)
			(layer "F.Fab")
			(effects
				(font
					(size 1.27 1.27)
				)
			)
		)
		(duplicate_pad_numbers_are_jumpers no)
		(fp_line
			(start 0.7874 0.4064)
			(end -0.7874 0.4064)
			(stroke
				(width 0.1524)
				(type default)
			)
			(layer "F.SilkS")
		)
		(fp_line
			(start 0.7874 -0.4064)
			(end 0.7874 0.4064)
			(stroke
				(width 0.1524)
				(type default)
			)
			(layer "F.SilkS")
		)
		(fp_line
			(start -0.7874 0.4064)
			(end -0.7874 -0.4064)
			(stroke
				(width 0.1524)
				(type default)
			)
			(layer "F.SilkS")
		)
		(fp_line
			(start -0.7874 -0.4064)
			(end 0.7874 -0.4064)
			(stroke
				(width 0.1524)
				(type default)
			)
			(layer "F.SilkS")
		)
		(fp_line
			(start 0.67945 0.3048)
			(end 0.120396 0.3048)
			(stroke
				(width 0.1)
				(type default)
			)
			(layer "F.Fab")
		)
		(fp_line
			(start 0.67945 -0.3048)
			(end 0.67945 0.3048)
			(stroke
				(width 0.1)
				(type default)
			)
			(layer "F.Fab")
		)
		(fp_line
			(start 0.12065 -0.2794)
			(end 0.12065 -0.3048)
			(stroke
				(width 0.1)
				(type default)
			)
			(layer "F.Fab")
		)
		(fp_line
			(start 0.12065 -0.3048)
			(end 0.67945 -0.3048)
			(stroke
				(width 0.1)
				(type default)
			)
			(layer "F.Fab")
		)
		(fp_line
			(start 0.120396 0.3048)
			(end 0.120396 0.2794)
			(stroke
				(width 0.1)
				(type default)
			)
			(layer "F.Fab")
		)
		(fp_line
			(start 0.120396 0.2794)
			(end -0.12065 0.2794)
			(stroke
				(width 0.1)
				(type default)
			)
			(layer "F.Fab")
		)
		(fp_line
			(start -0.12065 0.3048)
			(end -0.67945 0.3048)
			(stroke
				(width 0.1)
				(type default)
			)
			(layer "F.Fab")
		)
		(fp_line
			(start -0.12065 0.2794)
			(end -0.12065 0.3048)
			(stroke
				(width 0.1)
				(type default)
			)
			(layer "F.Fab")
		)
		(fp_line
			(start -0.12065 -0.2794)
			(end 0.12065 -0.2794)
			(stroke
				(width 0.1)
				(type default)
			)
			(layer "F.Fab")
		)
		(fp_line
			(start -0.12065 -0.305054)
			(end -0.12065 -0.2794)
			(stroke
				(width 0.1)
				(type default)
			)
			(layer "F.Fab")
		)
		(fp_line
			(start -0.67945 0.3048)
			(end -0.67945 -0.305054)
			(stroke
				(width 0.1)
				(type default)
			)
			(layer "F.Fab")
		)
		(fp_line
			(start -0.67945 -0.305054)
			(end -0.12065 -0.305054)
			(stroke
				(width 0.1)
				(type default)
			)
			(layer "F.Fab")
		)
		(pad "1" smd circle
			(at -0.40005 0 180)
			(size 0 0)
			(layers "F.Cu" "F.Mask" "F.Paste")
			(net "SMB_BIC_I2C9_MUX0_SSD6_R_SDA")
		)
		(pad "2" smd circle
			(at 0.40005 0 180)
			(size 0 0)
			(layers "F.Cu" "F.Mask" "F.Paste")
			(net "SMB_BIC_I2C9_MUX0_SSD6_SDA")
		)
	)
	(footprint ""
		(layer "F.Cu")
		(at 288.083498 -61.487812 180)
		(property "Reference" "R6004"
			(at 0 0 180)
			(layer "F.SilkS")
			(hide yes)
			(effects
				(font
					(size 1.27 1.27)
				)
			)
		)
		(property "Value" ""
			(at 0 0 180)
			(layer "F.Fab")
			(effects
				(font
					(size 1.27 1.27)
				)
			)
		)
		(duplicate_pad_numbers_are_jumpers no)
		(fp_line
			(start 0.7874 0.4064)
			(end -0.7874 0.4064)
			(stroke
				(width 0.1524)
				(type default)
			)
			(layer "F.SilkS")
		)
		(fp_line
			(start 0.7874 -0.4064)
			(end 0.7874 0.4064)
			(stroke
				(width 0.1524)
				(type default)
			)
			(layer "F.SilkS")
		)
		(fp_line
			(start -0.7874 0.4064)
			(end -0.7874 -0.4064)
			(stroke
				(width 0.1524)
				(type default)
			)
			(layer "F.SilkS")
		)
		(fp_line
			(start -0.7874 -0.4064)
			(end 0.7874 -0.4064)
			(stroke
				(width 0.1524)
				(type default)
			)
			(layer "F.SilkS")
		)
		(fp_line
			(start 0.67945 0.3048)
			(end 0.120396 0.3048)
			(stroke
				(width 0.1)
				(type default)
			)
			(layer "F.Fab")
		)
		(fp_line
			(start 0.67945 -0.3048)
			(end 0.67945 0.3048)
			(stroke
				(width 0.1)
				(type default)
			)
			(layer "F.Fab")
		)
		(fp_line
			(start 0.12065 -0.2794)
			(end 0.12065 -0.3048)
			(stroke
				(width 0.1)
				(type default)
			)
			(layer "F.Fab")
		)
		(fp_line
			(start 0.12065 -0.3048)
			(end 0.67945 -0.3048)
			(stroke
				(width 0.1)
				(type default)
			)
			(layer "F.Fab")
		)
		(fp_line
			(start 0.120396 0.3048)
			(end 0.120396 0.2794)
			(stroke
				(width 0.1)
				(type default)
			)
			(layer "F.Fab")
		)
		(fp_line
			(start 0.120396 0.2794)
			(end -0.12065 0.2794)
			(stroke
				(width 0.1)
				(type default)
			)
			(layer "F.Fab")
		)
		(fp_line
			(start -0.12065 0.3048)
			(end -0.67945 0.3048)
			(stroke
				(width 0.1)
				(type default)
			)
			(layer "F.Fab")
		)
		(fp_line
			(start -0.12065 0.2794)
			(end -0.12065 0.3048)
			(stroke
				(width 0.1)
				(type default)
			)
			(layer "F.Fab")
		)
		(fp_line
			(start -0.12065 -0.2794)
			(end 0.12065 -0.2794)
			(stroke
				(width 0.1)
				(type default)
			)
			(layer "F.Fab")
		)
		(fp_line
			(start -0.12065 -0.305054)
			(end -0.12065 -0.2794)
			(stroke
				(width 0.1)
				(type default)
			)
			(layer "F.Fab")
		)
		(fp_line
			(start -0.67945 0.3048)
			(end -0.67945 -0.305054)
			(stroke
				(width 0.1)
				(type default)
			)
			(layer "F.Fab")
		)
		(fp_line
			(start -0.67945 -0.305054)
			(end -0.12065 -0.305054)
			(stroke
				(width 0.1)
				(type default)
			)
			(layer "F.Fab")
		)
		(pad "1" smd circle
			(at -0.40005 0 180)
			(size 0 0)
			(layers "F.Cu" "F.Mask" "F.Paste")
			(net "PWRGD_P12V_SSD10_D")
		)
		(pad "2" smd circle
			(at 0.40005 0 180)
			(size 0 0)
			(layers "F.Cu" "F.Mask" "F.Paste")
			(net "PWRGD_P12V_SSD10_R")
		)
	)
	(footprint ""
		(layer "F.Cu")
		(at 354.166932 -52.543456 180)
		(property "Reference" "PC550"
			(at 0 0 180)
			(layer "F.SilkS")
			(hide yes)
			(effects
				(font
					(size 1.27 1.27)
				)
			)
		)
		(property "Value" ""
			(at 0 0 180)
			(layer "F.Fab")
			(effects
				(font
					(size 1.27 1.27)
				)
			)
		)
		(duplicate_pad_numbers_are_jumpers no)
		(fp_line
			(start 0.7874 0.4064)
			(end -0.7874 0.4064)
			(stroke
				(width 0.1524)
				(type default)
			)
			(layer "F.SilkS")
		)
		(fp_line
			(start 0.7874 -0.4064)
			(end 0.7874 0.4064)
			(stroke
				(width 0.1524)
				(type default)
			)
			(layer "F.SilkS")
		)
		(fp_line
			(start -0.7874 0.4064)
			(end -0.7874 -0.4064)
			(stroke
				(width 0.1524)
				(type default)
			)
			(layer "F.SilkS")
		)
		(fp_line
			(start -0.7874 -0.4064)
			(end 0.7874 -0.4064)
			(stroke
				(width 0.1524)
				(type default)
			)
			(layer "F.SilkS")
		)
		(fp_line
			(start 0.67945 0.3048)
			(end 0.120396 0.3048)
			(stroke
				(width 0.1)
				(type default)
			)
			(layer "F.Fab")
		)
		(fp_line
			(start 0.67945 -0.3048)
			(end 0.67945 0.3048)
			(stroke
				(width 0.1)
				(type default)
			)
			(layer "F.Fab")
		)
		(fp_line
			(start 0.12065 -0.2794)
			(end 0.12065 -0.3048)
			(stroke
				(width 0.1)
				(type default)
			)
			(layer "F.Fab")
		)
		(fp_line
			(start 0.12065 -0.3048)
			(end 0.67945 -0.3048)
			(stroke
				(width 0.1)
				(type default)
			)
			(layer "F.Fab")
		)
		(fp_line
			(start 0.120396 0.3048)
			(end 0.120396 0.2794)
			(stroke
				(width 0.1)
				(type default)
			)
			(layer "F.Fab")
		)
		(fp_line
			(start 0.120396 0.2794)
			(end -0.12065 0.2794)
			(stroke
				(width 0.1)
				(type default)
			)
			(layer "F.Fab")
		)
		(fp_line
			(start -0.12065 0.3048)
			(end -0.67945 0.3048)
			(stroke
				(width 0.1)
				(type default)
			)
			(layer "F.Fab")
		)
		(fp_line
			(start -0.12065 0.2794)
			(end -0.12065 0.3048)
			(stroke
				(width 0.1)
				(type default)
			)
			(layer "F.Fab")
		)
		(fp_line
			(start -0.12065 -0.2794)
			(end 0.12065 -0.2794)
			(stroke
				(width 0.1)
				(type default)
			)
			(layer "F.Fab")
		)
		(fp_line
			(start -0.12065 -0.305054)
			(end -0.12065 -0.2794)
			(stroke
				(width 0.1)
				(type default)
			)
			(layer "F.Fab")
		)
		(fp_line
			(start -0.67945 0.3048)
			(end -0.67945 -0.305054)
			(stroke
				(width 0.1)
				(type default)
			)
			(layer "F.Fab")
		)
		(fp_line
			(start -0.67945 -0.305054)
			(end -0.12065 -0.305054)
			(stroke
				(width 0.1)
				(type default)
			)
			(layer "F.Fab")
		)
		(pad "1" smd circle
			(at -0.40005 0 180)
			(size 0 0)
			(layers "F.Cu" "F.Mask" "F.Paste")
			(net "P3V3_SSD12")
		)
		(pad "2" smd circle
			(at 0.40005 0 180)
			(size 0 0)
			(layers "F.Cu" "F.Mask" "F.Paste")
			(net "GND")
		)
	)
	(footprint ""
		(layer "F.Cu")
		(at 418.596572 -350.098614 90)
		(property "Reference" "C816"
			(at 0 0 90)
			(layer "F.SilkS")
			(hide yes)
			(effects
				(font
					(size 1.27 1.27)
				)
			)
		)
		(property "Value" ""
			(at 0 0 90)
			(layer "F.Fab")
			(effects
				(font
					(size 1.27 1.27)
				)
			)
		)
		(duplicate_pad_numbers_are_jumpers no)
		(fp_line
			(start 0.299974 -0.150114)
			(end 0.299974 0.150114)
			(stroke
				(width 0.1)
				(type default)
			)
			(layer "F.Fab")
		)
		(fp_line
			(start -0.299974 -0.150114)
			(end 0.299974 -0.150114)
			(stroke
				(width 0.1)
				(type default)
			)
			(layer "F.Fab")
		)
		(fp_line
			(start 0.299974 0.150114)
			(end -0.299974 0.150114)
			(stroke
				(width 0.1)
				(type default)
			)
			(layer "F.Fab")
		)
		(fp_line
			(start -0.299974 0.150114)
			(end -0.299974 -0.150114)
			(stroke
				(width 0.1)
				(type default)
			)
			(layer "F.Fab")
		)
		(pad "1" smd rect
			(at -0.2667 0 90)
			(size 0.3048 0.381)
			(layers "F.Cu" "F.Mask" "F.Paste")
			(net "P5E_PEX3_STN7_TX_DP<116>")
		)
		(pad "2" smd rect
			(at 0.2667 0 90)
			(size 0.3048 0.381)
			(layers "F.Cu" "F.Mask" "F.Paste")
			(net "P5E_PEX3_STN7_TX_C_DP<116>")
		)
	)
	(footprint ""
		(layer "F.Cu")
		(at 141.164564 -29.079952 180)
		(property "Reference" "R6202"
			(at 0 0 180)
			(layer "F.SilkS")
			(hide yes)
			(effects
				(font
					(size 1.27 1.27)
				)
			)
		)
		(property "Value" ""
			(at 0 0 180)
			(layer "F.Fab")
			(effects
				(font
					(size 1.27 1.27)
				)
			)
		)
		(duplicate_pad_numbers_are_jumpers no)
		(fp_line
			(start 0.7874 0.4064)
			(end -0.7874 0.4064)
			(stroke
				(width 0.1524)
				(type default)
			)
			(layer "F.SilkS")
		)
		(fp_line
			(start 0.7874 -0.4064)
			(end 0.7874 0.4064)
			(stroke
				(width 0.1524)
				(type default)
			)
			(layer "F.SilkS")
		)
		(fp_line
			(start -0.7874 0.4064)
			(end -0.7874 -0.4064)
			(stroke
				(width 0.1524)
				(type default)
			)
			(layer "F.SilkS")
		)
		(fp_line
			(start -0.7874 -0.4064)
			(end 0.7874 -0.4064)
			(stroke
				(width 0.1524)
				(type default)
			)
			(layer "F.SilkS")
		)
		(fp_line
			(start 0.67945 0.3048)
			(end 0.120396 0.3048)
			(stroke
				(width 0.1)
				(type default)
			)
			(layer "F.Fab")
		)
		(fp_line
			(start 0.67945 -0.3048)
			(end 0.67945 0.3048)
			(stroke
				(width 0.1)
				(type default)
			)
			(layer "F.Fab")
		)
		(fp_line
			(start 0.12065 -0.2794)
			(end 0.12065 -0.3048)
			(stroke
				(width 0.1)
				(type default)
			)
			(layer "F.Fab")
		)
		(fp_line
			(start 0.12065 -0.3048)
			(end 0.67945 -0.3048)
			(stroke
				(width 0.1)
				(type default)
			)
			(layer "F.Fab")
		)
		(fp_line
			(start 0.120396 0.3048)
			(end 0.120396 0.2794)
			(stroke
				(width 0.1)
				(type default)
			)
			(layer "F.Fab")
		)
		(fp_line
			(start 0.120396 0.2794)
			(end -0.12065 0.2794)
			(stroke
				(width 0.1)
				(type default)
			)
			(layer "F.Fab")
		)
		(fp_line
			(start -0.12065 0.3048)
			(end -0.67945 0.3048)
			(stroke
				(width 0.1)
				(type default)
			)
			(layer "F.Fab")
		)
		(fp_line
			(start -0.12065 0.2794)
			(end -0.12065 0.3048)
			(stroke
				(width 0.1)
				(type default)
			)
			(layer "F.Fab")
		)
		(fp_line
			(start -0.12065 -0.2794)
			(end 0.12065 -0.2794)
			(stroke
				(width 0.1)
				(type default)
			)
			(layer "F.Fab")
		)
		(fp_line
			(start -0.12065 -0.305054)
			(end -0.12065 -0.2794)
			(stroke
				(width 0.1)
				(type default)
			)
			(layer "F.Fab")
		)
		(fp_line
			(start -0.67945 0.3048)
			(end -0.67945 -0.305054)
			(stroke
				(width 0.1)
				(type default)
			)
			(layer "F.Fab")
		)
		(fp_line
			(start -0.67945 -0.305054)
			(end -0.12065 -0.305054)
			(stroke
				(width 0.1)
				(type default)
			)
			(layer "F.Fab")
		)
		(pad "1" smd circle
			(at -0.40005 0 180)
			(size 0 0)
			(layers "F.Cu" "F.Mask" "F.Paste")
			(net "GND")
		)
		(pad "2" smd circle
			(at 0.40005 0 180)
			(size 0 0)
			(layers "F.Cu" "F.Mask" "F.Paste")
			(net "SSD4_PWRDIS_R")
		)
	)
	(footprint ""
		(layer "F.Cu")
		(at 321.205098 -298.87291 -90)
		(property "Reference" "R3971"
			(at 0 0 270)
			(layer "F.SilkS")
			(hide yes)
			(effects
				(font
					(size 1.27 1.27)
				)
			)
		)
		(property "Value" ""
			(at 0 0 270)
			(layer "F.Fab")
			(effects
				(font
					(size 1.27 1.27)
				)
			)
		)
		(duplicate_pad_numbers_are_jumpers no)
		(fp_line
			(start -0.7874 0.4064)
			(end -0.7874 -0.4064)
			(stroke
				(width 0.1524)
				(type default)
			)
			(layer "F.SilkS")
		)
		(fp_line
			(start 0.7874 0.4064)
			(end -0.7874 0.4064)
			(stroke
				(width 0.1524)
				(type default)
			)
			(layer "F.SilkS")
		)
		(fp_line
			(start -0.7874 -0.4064)
			(end 0.7874 -0.4064)
			(stroke
				(width 0.1524)
				(type default)
			)
			(layer "F.SilkS")
		)
		(fp_line
			(start 0.7874 -0.4064)
			(end 0.7874 0.4064)
			(stroke
				(width 0.1524)
				(type default)
			)
			(layer "F.SilkS")
		)
		(fp_line
			(start -0.67945 0.3048)
			(end -0.67945 -0.305054)
			(stroke
				(width 0.1)
				(type default)
			)
			(layer "F.Fab")
		)
		(fp_line
			(start -0.12065 0.3048)
			(end -0.67945 0.3048)
			(stroke
				(width 0.1)
				(type default)
			)
			(layer "F.Fab")
		)
		(fp_line
			(start 0.120396 0.3048)
			(end 0.120396 0.2794)
			(stroke
				(width 0.1)
				(type default)
			)
			(layer "F.Fab")
		)
		(fp_line
			(start 0.67945 0.3048)
			(end 0.120396 0.3048)
			(stroke
				(width 0.1)
				(type default)
			)
			(layer "F.Fab")
		)
		(fp_line
			(start -0.12065 0.2794)
			(end -0.12065 0.3048)
			(stroke
				(width 0.1)
				(type default)
			)
			(layer "F.Fab")
		)
		(fp_line
			(start 0.120396 0.2794)
			(end -0.12065 0.2794)
			(stroke
				(width 0.1)
				(type default)
			)
			(layer "F.Fab")
		)
		(fp_line
			(start -0.12065 -0.2794)
			(end 0.12065 -0.2794)
			(stroke
				(width 0.1)
				(type default)
			)
			(layer "F.Fab")
		)
		(fp_line
			(start 0.12065 -0.2794)
			(end 0.12065 -0.3048)
			(stroke
				(width 0.1)
				(type default)
			)
			(layer "F.Fab")
		)
		(fp_line
			(start 0.12065 -0.3048)
			(end 0.67945 -0.3048)
			(stroke
				(width 0.1)
				(type default)
			)
			(layer "F.Fab")
		)
		(fp_line
			(start 0.67945 -0.3048)
			(end 0.67945 0.3048)
			(stroke
				(width 0.1)
				(type default)
			)
			(layer "F.Fab")
		)
		(fp_line
			(start -0.67945 -0.305054)
			(end -0.12065 -0.305054)
			(stroke
				(width 0.1)
				(type default)
			)
			(layer "F.Fab")
		)
		(fp_line
			(start -0.12065 -0.305054)
			(end -0.12065 -0.2794)
			(stroke
				(width 0.1)
				(type default)
			)
			(layer "F.Fab")
		)
		(pad "1" smd circle
			(at -0.40005 0 270)
			(size 0 0)
			(layers "F.Cu" "F.Mask" "F.Paste")
			(net "I2C_PEX2_HOST_SDA")
		)
		(pad "2" smd circle
			(at 0.40005 0 270)
			(size 0 0)
			(layers "F.Cu" "F.Mask" "F.Paste")
			(net "I2C_PEX2_HOST_R_SDA")
		)
	)
	(footprint ""
		(layer "F.Cu")
		(at 169.22623 -37.929566 90)
		(property "Reference" "R5558"
			(at 0 0 90)
			(layer "F.SilkS")
			(hide yes)
			(effects
				(font
					(size 1.27 1.27)
				)
			)
		)
		(property "Value" ""
			(at 0 0 90)
			(layer "F.Fab")
			(effects
				(font
					(size 1.27 1.27)
				)
			)
		)
		(duplicate_pad_numbers_are_jumpers no)
		(fp_line
			(start 0.7874 -0.4064)
			(end 0.7874 0.4064)
			(stroke
				(width 0.1524)
				(type default)
			)
			(layer "F.SilkS")
		)
		(fp_line
			(start -0.7874 -0.4064)
			(end 0.7874 -0.4064)
			(stroke
				(width 0.1524)
				(type default)
			)
			(layer "F.SilkS")
		)
		(fp_line
			(start 0.7874 0.4064)
			(end -0.7874 0.4064)
			(stroke
				(width 0.1524)
				(type default)
			)
			(layer "F.SilkS")
		)
		(fp_line
			(start -0.7874 0.4064)
			(end -0.7874 -0.4064)
			(stroke
				(width 0.1524)
				(type default)
			)
			(layer "F.SilkS")
		)
		(fp_line
			(start -0.12065 -0.305054)
			(end -0.12065 -0.2794)
			(stroke
				(width 0.1)
				(type default)
			)
			(layer "F.Fab")
		)
		(fp_line
			(start -0.67945 -0.305054)
			(end -0.12065 -0.305054)
			(stroke
				(width 0.1)
				(type default)
			)
			(layer "F.Fab")
		)
		(fp_line
			(start 0.67945 -0.3048)
			(end 0.67945 0.3048)
			(stroke
				(width 0.1)
				(type default)
			)
			(layer "F.Fab")
		)
		(fp_line
			(start 0.12065 -0.3048)
			(end 0.67945 -0.3048)
			(stroke
				(width 0.1)
				(type default)
			)
			(layer "F.Fab")
		)
		(fp_line
			(start 0.12065 -0.2794)
			(end 0.12065 -0.3048)
			(stroke
				(width 0.1)
				(type default)
			)
			(layer "F.Fab")
		)
		(fp_line
			(start -0.12065 -0.2794)
			(end 0.12065 -0.2794)
			(stroke
				(width 0.1)
				(type default)
			)
			(layer "F.Fab")
		)
		(fp_line
			(start 0.120396 0.2794)
			(end -0.12065 0.2794)
			(stroke
				(width 0.1)
				(type default)
			)
			(layer "F.Fab")
		)
		(fp_line
			(start -0.12065 0.2794)
			(end -0.12065 0.3048)
			(stroke
				(width 0.1)
				(type default)
			)
			(layer "F.Fab")
		)
		(fp_line
			(start 0.67945 0.3048)
			(end 0.120396 0.3048)
			(stroke
				(width 0.1)
				(type default)
			)
			(layer "F.Fab")
		)
		(fp_line
			(start 0.120396 0.3048)
			(end 0.120396 0.2794)
			(stroke
				(width 0.1)
				(type default)
			)
			(layer "F.Fab")
		)
		(fp_line
			(start -0.12065 0.3048)
			(end -0.67945 0.3048)
			(stroke
				(width 0.1)
				(type default)
			)
			(layer "F.Fab")
		)
		(fp_line
			(start -0.67945 0.3048)
			(end -0.67945 -0.305054)
			(stroke
				(width 0.1)
				(type default)
			)
			(layer "F.Fab")
		)
		(pad "1" smd circle
			(at -0.40005 0 90)
			(size 0 0)
			(layers "F.Cu" "F.Mask" "F.Paste")
			(net "SSD6_AUX_P3V3_EN_R")
		)
		(pad "2" smd circle
			(at 0.40005 0 90)
			(size 0 0)
			(layers "F.Cu" "F.Mask" "F.Paste")
			(net "SSD6_AUX_P3V3_EN")
		)
	)
)
